# S9S_MB_2U (Grand Teton) — schematic netlist excerpt (pin names and nets, part order shuffled) for the footprints in the layout excerpt that follows; sources: Cadence DE-HDL packaged netlist, KiCad conversion of 03242023_DA0F0TMBIJ0_F0T_Motherboard_J_brd_V01_OCP.brd

PC203_P0_2  Q_CAP  22UF 4V 20% X6S  pkg C0805  page 275 : A = PVCCINFAON_CPU0 ; B = GND
R2664  Q_RES  33.2 1% CHIP  pkg 0402LF  page 213 : A = FM_GPU_PWRGD_ISO ; B = FM_GPU_PWRGD_ISO_R
R1464  Q_RES  0 5% CHIP  pkg 0402LF  page 189 : A = P1V8_PCH_AUX ; B = P1V8_PCH_PLL_AUX

(kicad_pcb
	(version 20260206)
	(generator "pcbnew")
	(generator_version "10.0")
	(general
		(thickness 1.6)
		(legacy_teardrops no)
	)
	(paper "A4")
	(title_block
		(title "03242023_DA0F0TMBIJ0_F0T_Motherboard_J_brd_V01_OCP.brd")
		(comment 1 "Grand Teton / footprints 5219-5221 of 6105")
	)
	(layers
		(0 "F.Cu" signal "TOP")
		(4 "In1.Cu" signal "GND")
		(6 "In2.Cu" signal "IN1")
		(8 "In3.Cu" signal "GND1")
		(10 "In4.Cu" signal "IN2")
		(12 "In5.Cu" signal "GND2")
		(14 "In6.Cu" signal "IN3")
		(16 "In7.Cu" signal "GND3")
		(18 "In8.Cu" signal "VCC")
		(20 "In9.Cu" signal "VCC1")
		(22 "In10.Cu" signal "GND4")
		(24 "In11.Cu" signal "IN4")
		(26 "In12.Cu" signal "GND5")
		(28 "In13.Cu" signal "IN5")
		(30 "In14.Cu" signal "GND6")
		(32 "In15.Cu" signal "IN6")
		(34 "In16.Cu" signal "GND7")
		(2 "B.Cu" signal "BOTTOM")
		(9 "F.Adhes" user "F.Adhesive")
		(11 "B.Adhes" user "B.Adhesive")
		(13 "F.Paste" user "Package Geometry/Pastemask Top")
		(15 "B.Paste" user "Package Geometry/Pastemask Bottom")
		(5 "F.SilkS" user "Ref Des/Silkscreen Top")
		(7 "B.SilkS" user "Ref Des/Silkscreen Bottom")
		(1 "F.Mask" user "Board Geometry/Soldermask Top")
		(3 "B.Mask" user "Board Geometry/Soldermask Bottom")
		(17 "Dwgs.User" user "User.Drawings")
		(19 "Cmts.User" user "User.Comments")
		(21 "Eco1.User" user "User.Eco1")
		(23 "Eco2.User" user "User.Eco2")
		(25 "Edge.Cuts" user "Board Geometry/Outline")
		(27 "Margin" user)
		(31 "F.CrtYd" user "Package Geometry/Place Bound Top")
		(29 "B.CrtYd" user "Package Geometry/Place Bound Bottom")
		(35 "F.Fab" user "Ref Des/Assembly Top")
		(33 "B.Fab" user "Ref Des/Assembly Bottom")
	)
	(footprint ""
		(layer "B.Cu")
		(at 353.551998 -56.833516)
		(property "Reference" "R1464"
			(at 0 0 0)
			(layer "B.SilkS")
			(hide yes)
			(effects
				(font
					(size 1.27 1.27)
				)
				(justify mirror)
			)
		)
		(property "Value" ""
			(at 0 0 0)
			(layer "B.Fab")
			(effects
				(font
					(size 1.27 1.27)
				)
				(justify mirror)
			)
		)
		(duplicate_pad_numbers_are_jumpers no)
		(fp_line
			(start -0.7874 -0.4064)
			(end -0.7874 0.4064)
			(stroke
				(width 0.1524)
				(type default)
			)
			(layer "B.SilkS")
		)
		(fp_line
			(start -0.7874 0.4064)
			(end 0.7874 0.4064)
			(stroke
				(width 0.1524)
				(type default)
			)
			(layer "B.SilkS")
		)
		(fp_line
			(start 0.7874 -0.4064)
			(end -0.7874 -0.4064)
			(stroke
				(width 0.1524)
				(type default)
			)
			(layer "B.SilkS")
		)
		(fp_line
			(start 0.7874 0.4064)
			(end 0.7874 -0.4064)
			(stroke
				(width 0.1524)
				(type default)
			)
			(layer "B.SilkS")
		)
		(fp_line
			(start -0.67945 -0.3048)
			(end -0.67945 0.3048)
			(stroke
				(width 0.1)
				(type default)
			)
			(layer "B.Fab")
		)
		(fp_line
			(start -0.67945 0.3048)
			(end -0.120396 0.3048)
			(stroke
				(width 0.1)
				(type default)
			)
			(layer "B.Fab")
		)
		(fp_line
			(start -0.12065 -0.3048)
			(end -0.67945 -0.3048)
			(stroke
				(width 0.1)
				(type default)
			)
			(layer "B.Fab")
		)
		(fp_line
			(start -0.12065 -0.2794)
			(end -0.12065 -0.3048)
			(stroke
				(width 0.1)
				(type default)
			)
			(layer "B.Fab")
		)
		(fp_line
			(start -0.120396 0.2794)
			(end 0.12065 0.2794)
			(stroke
				(width 0.1)
				(type default)
			)
			(layer "B.Fab")
		)
		(fp_line
			(start -0.120396 0.3048)
			(end -0.120396 0.2794)
			(stroke
				(width 0.1)
				(type default)
			)
			(layer "B.Fab")
		)
		(fp_line
			(start 0.12065 -0.305054)
			(end 0.12065 -0.2794)
			(stroke
				(width 0.1)
				(type default)
			)
			(layer "B.Fab")
		)
		(fp_line
			(start 0.12065 -0.2794)
			(end -0.12065 -0.2794)
			(stroke
				(width 0.1)
				(type default)
			)
			(layer "B.Fab")
		)
		(fp_line
			(start 0.12065 0.2794)
			(end 0.12065 0.3048)
			(stroke
				(width 0.1)
				(type default)
			)
			(layer "B.Fab")
		)
		(fp_line
			(start 0.12065 0.3048)
			(end 0.67945 0.3048)
			(stroke
				(width 0.1)
				(type default)
			)
			(layer "B.Fab")
		)
		(fp_line
			(start 0.67945 -0.305054)
			(end 0.12065 -0.305054)
			(stroke
				(width 0.1)
				(type default)
			)
			(layer "B.Fab")
		)
		(fp_line
			(start 0.67945 0.3048)
			(end 0.67945 -0.305054)
			(stroke
				(width 0.1)
				(type default)
			)
			(layer "B.Fab")
		)
		(pad "1" smd circle
			(at 0.40005 0 180)
			(size 0 0)
			(layers "B.Cu" "B.Mask" "B.Paste")
			(net "P1V8_PCH_AUX")
		)
		(pad "2" smd circle
			(at -0.40005 0 180)
			(size 0 0)
			(layers "B.Cu" "B.Mask" "B.Paste")
			(net "P1V8_PCH_PLL_AUX")
		)
	)
	(footprint ""
		(layer "B.Cu")
		(at 407.91257 -175.986948 180)
		(property "Reference" "PC203_P0_2"
			(at 0 0 0)
			(layer "B.SilkS")
			(hide yes)
			(effects
				(font
					(size 1.27 1.27)
				)
				(justify mirror)
			)
		)
		(property "Value" ""
			(at 0 0 0)
			(layer "B.Fab")
			(effects
				(font
					(size 1.27 1.27)
				)
				(justify mirror)
			)
		)
		(duplicate_pad_numbers_are_jumpers no)
		(fp_line
			(start 1.524 0.762)
			(end 1.524 -0.762)
			(stroke
				(width 0.1524)
				(type default)
			)
			(layer "B.SilkS")
		)
		(fp_line
			(start 1.524 -0.762)
			(end -1.524 -0.762)
			(stroke
				(width 0.1524)
				(type default)
			)
			(layer "B.SilkS")
		)
		(fp_line
			(start -1.524 0.762)
			(end 1.524 0.762)
			(stroke
				(width 0.1524)
				(type default)
			)
			(layer "B.SilkS")
		)
		(fp_line
			(start -1.524 -0.762)
			(end -1.524 0.762)
			(stroke
				(width 0.1524)
				(type default)
			)
			(layer "B.SilkS")
		)
		(fp_line
			(start 1.1049 0.724916)
			(end -1.1049 0.724916)
			(stroke
				(width 0.1)
				(type default)
			)
			(layer "B.Fab")
		)
		(fp_line
			(start 1.1049 -0.724916)
			(end 1.1049 0.724916)
			(stroke
				(width 0.1)
				(type default)
			)
			(layer "B.Fab")
		)
		(fp_line
			(start -1.1049 0.724916)
			(end -1.1049 -0.724916)
			(stroke
				(width 0.1)
				(type default)
			)
			(layer "B.Fab")
		)
		(fp_line
			(start -1.1049 -0.724916)
			(end 1.1049 -0.724916)
			(stroke
				(width 0.1)
				(type default)
			)
			(layer "B.Fab")
		)
		(pad "1" smd rect
			(at 0.889 0 180)
			(size 1.016 1.27)
			(layers "B.Cu" "B.Mask" "B.Paste")
			(net "PVCCINFAON_CPU0")
		)
		(pad "2" smd rect
			(at -0.889 0 180)
			(size 1.016 1.27)
			(layers "B.Cu" "B.Mask" "B.Paste")
			(net "GND")
		)
	)
	(footprint ""
		(layer "B.Cu")
		(at 164.64788 -109.565948 180)
		(property "Reference" "R2664"
			(at 0 0 0)
			(layer "B.SilkS")
			(hide yes)
			(effects
				(font
					(size 1.27 1.27)
				)
				(justify mirror)
			)
		)
		(property "Value" ""
			(at 0 0 0)
			(layer "B.Fab")
			(effects
				(font
					(size 1.27 1.27)
				)
				(justify mirror)
			)
		)
		(duplicate_pad_numbers_are_jumpers no)
		(fp_line
			(start 0.7874 0.4064)
			(end 0.7874 -0.4064)
			(stroke
				(width 0.1524)
				(type default)
			)
			(layer "B.SilkS")
		)
		(fp_line
			(start 0.7874 -0.4064)
			(end -0.7874 -0.4064)
			(stroke
				(width 0.1524)
				(type default)
			)
			(layer "B.SilkS")
		)
		(fp_line
			(start -0.7874 0.4064)
			(end 0.7874 0.4064)
			(stroke
				(width 0.1524)
				(type default)
			)
			(layer "B.SilkS")
		)
		(fp_line
			(start -0.7874 -0.4064)
			(end -0.7874 0.4064)
			(stroke
				(width 0.1524)
				(type default)
			)
			(layer "B.SilkS")
		)
		(fp_line
			(start 0.67945 0.3048)
			(end 0.67945 -0.305054)
			(stroke
				(width 0.1)
				(type default)
			)
			(layer "B.Fab")
		)
		(fp_line
			(start 0.67945 -0.305054)
			(end 0.12065 -0.305054)
			(stroke
				(width 0.1)
				(type default)
			)
			(layer "B.Fab")
		)
		(fp_line
			(start 0.12065 0.3048)
			(end 0.67945 0.3048)
			(stroke
				(width 0.1)
				(type default)
			)
			(layer "B.Fab")
		)
		(fp_line
			(start 0.12065 0.2794)
			(end 0.12065 0.3048)
			(stroke
				(width 0.1)
				(type default)
			)
			(layer "B.Fab")
		)
		(fp_line
			(start 0.12065 -0.2794)
			(end -0.12065 -0.2794)
			(stroke
				(width 0.1)
				(type default)
			)
			(layer "B.Fab")
		)
		(fp_line
			(start 0.12065 -0.305054)
			(end 0.12065 -0.2794)
			(stroke
				(width 0.1)
				(type default)
			)
			(layer "B.Fab")
		)
		(fp_line
			(start -0.120396 0.3048)
			(end -0.120396 0.2794)
			(stroke
				(width 0.1)
				(type default)
			)
			(layer "B.Fab")
		)
		(fp_line
			(start -0.120396 0.2794)
			(end 0.12065 0.2794)
			(stroke
				(width 0.1)
				(type default)
			)
			(layer "B.Fab")
		)
		(fp_line
			(start -0.12065 -0.2794)
			(end -0.12065 -0.3048)
			(stroke
				(width 0.1)
				(type default)
			)
			(layer "B.Fab")
		)
		(fp_line
			(start -0.12065 -0.3048)
			(end -0.67945 -0.3048)
			(stroke
				(width 0.1)
				(type default)
			)
			(layer "B.Fab")
		)
		(fp_line
			(start -0.67945 0.3048)
			(end -0.120396 0.3048)
			(stroke
				(width 0.1)
				(type default)
			)
			(layer "B.Fab")
		)
		(fp_line
			(start -0.67945 -0.3048)
			(end -0.67945 0.3048)
			(stroke
				(width 0.1)
				(type default)
			)
			(layer "B.Fab")
		)
		(pad "1" smd circle
			(at 0.40005 0)
			(size 0 0)
			(layers "B.Cu" "B.Mask" "B.Paste")
			(net "FM_GPU_PWRGD_ISO")
		)
		(pad "2" smd circle
			(at -0.40005 0)
			(size 0 0)
			(layers "B.Cu" "B.Mask" "B.Paste")
			(net "FM_GPU_PWRGD_ISO_R")
		)
	)
)
